# T6G (Grand Teton) — schematic netlist excerpt (pin names and nets, part order shuffled) for the footprints in the layout excerpt that follows; sources: Cadence DE-HDL packaged netlist, KiCad conversion of 04192023_DAF0TMB3IC0_F0TG_MB_C_brd_V02_OCP.brd

R1062  Q_RES  10K 1% CHIP  pkg 0201LF  page 298 : A = RST_RT_CPU0_P2_RESET_R_N ; B = GND
R684  Q_RES  49.9 1% CHIP  pkg 0201LF  page 309 : A = SMB_RT_CPU0_P3_ROM_MUX_1D_SCL ; B = SMB_RT_CPU0_P3_ROM_MUX_1D_R_SCL
C363  Q_CAP  220PF 50V 5% C0G  pkg C0402  page 164 : A = UART_CPU0_LVC3_UART0_TX ; B = GND

(kicad_pcb
	(version 20260206)
	(generator "pcbnew")
	(generator_version "10.0")
	(general
		(thickness 1.6)
		(legacy_teardrops no)
	)
	(paper "A4")
	(title_block
		(title "04192023_DAF0TMB3IC0_F0TG_MB_C_brd_V02_OCP.brd")
		(comment 1 "Grand Teton / footprints 3529-3531 of 8354")
	)
	(layers
		(0 "F.Cu" signal "TOP")
		(4 "In1.Cu" signal "GND")
		(6 "In2.Cu" signal "IN1")
		(8 "In3.Cu" signal "GND1")
		(10 "In4.Cu" signal "IN2")
		(12 "In5.Cu" signal "GND2")
		(14 "In6.Cu" signal "IN3")
		(16 "In7.Cu" signal "GND3")
		(18 "In8.Cu" signal "VCC")
		(20 "In9.Cu" signal "VCC1")
		(22 "In10.Cu" signal "GND4")
		(24 "In11.Cu" signal "IN4")
		(26 "In12.Cu" signal "GND5")
		(28 "In13.Cu" signal "IN5")
		(30 "In14.Cu" signal "GND6")
		(32 "In15.Cu" signal "IN6")
		(34 "In16.Cu" signal "GND7")
		(2 "B.Cu" signal "BOTTOM")
		(9 "F.Adhes" user "F.Adhesive")
		(11 "B.Adhes" user "B.Adhesive")
		(13 "F.Paste" user "Package Geometry/Pastemask Top")
		(15 "B.Paste" user "Package Geometry/Pastemask Bottom")
		(5 "F.SilkS" user "Ref Des/Silkscreen Top")
		(7 "B.SilkS" user "Ref Des/Silkscreen Bottom")
		(1 "F.Mask" user "Board Geometry/Soldermask Top")
		(3 "B.Mask" user "Board Geometry/Soldermask Bottom")
		(17 "Dwgs.User" user "User.Drawings")
		(19 "Cmts.User" user "User.Comments")
		(21 "Eco1.User" user "User.Eco1")
		(23 "Eco2.User" user "User.Eco2")
		(25 "Edge.Cuts" user "Board Geometry/Outline")
		(27 "Margin" user)
		(31 "F.CrtYd" user "Package Geometry/Place Bound Top")
		(29 "B.CrtYd" user "Package Geometry/Place Bound Bottom")
		(35 "F.Fab" user "Ref Des/Assembly Top")
		(33 "B.Fab" user "Ref Des/Assembly Bottom")
	)
	(footprint ""
		(layer "F.Cu")
		(at 400.315684 -402.548852 -90)
		(property "Reference" "R1062"
			(at 0 0 270)
			(layer "F.SilkS")
			(hide yes)
			(effects
				(font
					(size 1.27 1.27)
				)
			)
		)
		(property "Value" ""
			(at 0 0 270)
			(layer "F.Fab")
			(effects
				(font
					(size 1.27 1.27)
				)
			)
		)
		(duplicate_pad_numbers_are_jumpers no)
		(fp_line
			(start -0.32512 0.175006)
			(end -0.32512 -0.175006)
			(stroke
				(width 0.1)
				(type default)
			)
			(layer "F.Fab")
		)
		(fp_line
			(start 0.32512 0.175006)
			(end -0.32512 0.175006)
			(stroke
				(width 0.1)
				(type default)
			)
			(layer "F.Fab")
		)
		(fp_line
			(start -0.32512 -0.175006)
			(end 0.32512 -0.175006)
			(stroke
				(width 0.1)
				(type default)
			)
			(layer "F.Fab")
		)
		(fp_line
			(start 0.32512 -0.175006)
			(end 0.32512 0.175006)
			(stroke
				(width 0.1)
				(type default)
			)
			(layer "F.Fab")
		)
		(pad "1" smd rect
			(at -0.2667 0 270)
			(size 0.3048 0.381)
			(layers "F.Cu" "F.Mask" "F.Paste")
			(net "RST_RT_CPU0_P2_RESET_R_N")
		)
		(pad "2" smd rect
			(at 0.2667 0 90)
			(size 0.3048 0.381)
			(layers "F.Cu" "F.Mask" "F.Paste")
			(net "GND")
		)
	)
	(footprint ""
		(layer "F.Cu")
		(at 365.794798 -428.28591 180)
		(property "Reference" "R684"
			(at 0 0 180)
			(layer "F.SilkS")
			(hide yes)
			(effects
				(font
					(size 1.27 1.27)
				)
			)
		)
		(property "Value" ""
			(at 0 0 180)
			(layer "F.Fab")
			(effects
				(font
					(size 1.27 1.27)
				)
			)
		)
		(duplicate_pad_numbers_are_jumpers no)
		(fp_line
			(start 0.32512 0.175006)
			(end -0.32512 0.175006)
			(stroke
				(width 0.1)
				(type default)
			)
			(layer "F.Fab")
		)
		(fp_line
			(start 0.32512 -0.175006)
			(end 0.32512 0.175006)
			(stroke
				(width 0.1)
				(type default)
			)
			(layer "F.Fab")
		)
		(fp_line
			(start -0.32512 0.175006)
			(end -0.32512 -0.175006)
			(stroke
				(width 0.1)
				(type default)
			)
			(layer "F.Fab")
		)
		(fp_line
			(start -0.32512 -0.175006)
			(end 0.32512 -0.175006)
			(stroke
				(width 0.1)
				(type default)
			)
			(layer "F.Fab")
		)
		(pad "1" smd rect
			(at -0.2667 0 180)
			(size 0.3048 0.381)
			(layers "F.Cu" "F.Mask" "F.Paste")
			(net "SMB_RT_CPU0_P3_ROM_MUX_1D_SCL")
		)
		(pad "2" smd rect
			(at 0.2667 0)
			(size 0.3048 0.381)
			(layers "F.Cu" "F.Mask" "F.Paste")
			(net "SMB_RT_CPU0_P3_ROM_MUX_1D_R_SCL")
		)
	)
	(footprint ""
		(layer "F.Cu")
		(at 367.504726 -27.904694 -90)
		(property "Reference" "C363"
			(at 0 0 270)
			(layer "F.SilkS")
			(hide yes)
			(effects
				(font
					(size 1.27 1.27)
				)
			)
		)
		(property "Value" ""
			(at 0 0 270)
			(layer "F.Fab")
			(effects
				(font
					(size 1.27 1.27)
				)
			)
		)
		(duplicate_pad_numbers_are_jumpers no)
		(fp_line
			(start -0.7874 0.4064)
			(end -0.7874 -0.4064)
			(stroke
				(width 0.1524)
				(type default)
			)
			(layer "F.SilkS")
		)
		(fp_line
			(start 0.7874 0.4064)
			(end -0.7874 0.4064)
			(stroke
				(width 0.1524)
				(type default)
			)
			(layer "F.SilkS")
		)
		(fp_line
			(start -0.7874 -0.4064)
			(end 0.7874 -0.4064)
			(stroke
				(width 0.1524)
				(type default)
			)
			(layer "F.SilkS")
		)
		(fp_line
			(start 0.7874 -0.4064)
			(end 0.7874 0.4064)
			(stroke
				(width 0.1524)
				(type default)
			)
			(layer "F.SilkS")
		)
		(fp_line
			(start -0.67945 0.3048)
			(end -0.67945 -0.305054)
			(stroke
				(width 0.1)
				(type default)
			)
			(layer "F.Fab")
		)
		(fp_line
			(start -0.12065 0.3048)
			(end -0.67945 0.3048)
			(stroke
				(width 0.1)
				(type default)
			)
			(layer "F.Fab")
		)
		(fp_line
			(start 0.120396 0.3048)
			(end 0.120396 0.2794)
			(stroke
				(width 0.1)
				(type default)
			)
			(layer "F.Fab")
		)
		(fp_line
			(start 0.67945 0.3048)
			(end 0.120396 0.3048)
			(stroke
				(width 0.1)
				(type default)
			)
			(layer "F.Fab")
		)
		(fp_line
			(start -0.12065 0.2794)
			(end -0.12065 0.3048)
			(stroke
				(width 0.1)
				(type default)
			)
			(layer "F.Fab")
		)
		(fp_line
			(start 0.120396 0.2794)
			(end -0.12065 0.2794)
			(stroke
				(width 0.1)
				(type default)
			)
			(layer "F.Fab")
		)
		(fp_line
			(start -0.12065 -0.2794)
			(end 0.12065 -0.2794)
			(stroke
				(width 0.1)
				(type default)
			)
			(layer "F.Fab")
		)
		(fp_line
			(start 0.12065 -0.2794)
			(end 0.12065 -0.3048)
			(stroke
				(width 0.1)
				(type default)
			)
			(layer "F.Fab")
		)
		(fp_line
			(start 0.12065 -0.3048)
			(end 0.67945 -0.3048)
			(stroke
				(width 0.1)
				(type default)
			)
			(layer "F.Fab")
		)
		(fp_line
			(start 0.67945 -0.3048)
			(end 0.67945 0.3048)
			(stroke
				(width 0.1)
				(type default)
			)
			(layer "F.Fab")
		)
		(fp_line
			(start -0.67945 -0.305054)
			(end -0.12065 -0.305054)
			(stroke
				(width 0.1)
				(type default)
			)
			(layer "F.Fab")
		)
		(fp_line
			(start -0.12065 -0.305054)
			(end -0.12065 -0.2794)
			(stroke
				(width 0.1)
				(type default)
			)
			(layer "F.Fab")
		)
		(pad "1" smd circle
			(at -0.40005 0 270)
			(size 0 0)
			(layers "F.Cu" "F.Mask" "F.Paste")
			(net "UART_CPU0_LVC3_UART0_TX")
		)
		(pad "2" smd circle
			(at 0.40005 0 270)
			(size 0 0)
			(layers "F.Cu" "F.Mask" "F.Paste")
			(net "GND")
		)
	)
)
